(kicad_pcb
	(version 20260206)
	(generator "pcbnew")
	(generator_version "10.0")
	(general
		(thickness 1.6)
		(legacy_teardrops no)
	)
	(paper "A4")
	(title_block
		(title "04192023_DAF0TMB3IC0_F0TG_MB_C_brd_V02_OCP.brd")
		(comment 1 "Grand Teton / footprints 1816-1821 of 8354")
	)
	(layers
		(0 "F.Cu" signal "TOP")
		(4 "In1.Cu" signal "GND")
		(6 "In2.Cu" signal "IN1")
		(8 "In3.Cu" signal "GND1")
		(10 "In4.Cu" signal "IN2")
		(12 "In5.Cu" signal "GND2")
		(14 "In6.Cu" signal "IN3")
		(16 "In7.Cu" signal "GND3")
		(18 "In8.Cu" signal "VCC")
		(20 "In9.Cu" signal "VCC1")
		(22 "In10.Cu" signal "GND4")
		(24 "In11.Cu" signal "IN4")
		(26 "In12.Cu" signal "GND5")
		(28 "In13.Cu" signal "IN5")
		(30 "In14.Cu" signal "GND6")
		(32 "In15.Cu" signal "IN6")
		(34 "In16.Cu" signal "GND7")
		(2 "B.Cu" signal "BOTTOM")
		(9 "F.Adhes" user "F.Adhesive")
		(11 "B.Adhes" user "B.Adhesive")
		(13 "F.Paste" user "Package Geometry/Pastemask Top")
		(15 "B.Paste" user "Package Geometry/Pastemask Bottom")
		(5 "F.SilkS" user "Ref Des/Silkscreen Top")
		(7 "B.SilkS" user "Ref Des/Silkscreen Bottom")
		(1 "F.Mask" user "Board Geometry/Soldermask Top")
		(3 "B.Mask" user "Board Geometry/Soldermask Bottom")
		(17 "Dwgs.User" user "User.Drawings")
		(19 "Cmts.User" user "User.Comments")
		(21 "Eco1.User" user "User.Eco1")
		(23 "Eco2.User" user "User.Eco2")
		(25 "Edge.Cuts" user "Board Geometry/Outline")
		(27 "Margin" user)
		(31 "F.CrtYd" user "Package Geometry/Place Bound Top")
		(29 "B.CrtYd" user "Package Geometry/Place Bound Bottom")
		(35 "F.Fab" user "Ref Des/Assembly Top")
		(33 "B.Fab" user "Ref Des/Assembly Bottom")
	)
	(footprint ""
		(layer "F.Cu")
		(at 219.347034 -75.02779 -90)
		(property "Reference" "PC2208"
			(at 0 0 270)
			(layer "F.SilkS")
			(hide yes)
			(effects
				(font
					(size 1.27 1.27)
				)
			)
		)
		(property "Value" ""
			(at 0 0 270)
			(layer "F.Fab")
			(effects
				(font
					(size 1.27 1.27)
				)
			)
		)
		(duplicate_pad_numbers_are_jumpers no)
		(fp_line
			(start -0.7874 0.4064)
			(end -0.7874 -0.4064)
			(stroke
				(width 0.1524)
				(type default)
			)
			(layer "F.SilkS")
		)
		(fp_line
			(start 0.7874 0.4064)
			(end -0.7874 0.4064)
			(stroke
				(width 0.1524)
				(type default)
			)
			(layer "F.SilkS")
		)
		(fp_line
			(start -0.7874 -0.4064)
			(end 0.7874 -0.4064)
			(stroke
				(width 0.1524)
				(type default)
			)
			(layer "F.SilkS")
		)
		(fp_line
			(start 0.7874 -0.4064)
			(end 0.7874 0.4064)
			(stroke
				(width 0.1524)
				(type default)
			)
			(layer "F.SilkS")
		)
		(fp_line
			(start -0.67945 0.3048)
			(end -0.67945 -0.305054)
			(stroke
				(width 0.1)
				(type default)
			)
			(layer "F.Fab")
		)
		(fp_line
			(start -0.12065 0.3048)
			(end -0.67945 0.3048)
			(stroke
				(width 0.1)
				(type default)
			)
			(layer "F.Fab")
		)
		(fp_line
			(start 0.120396 0.3048)
			(end 0.120396 0.2794)
			(stroke
				(width 0.1)
				(type default)
			)
			(layer "F.Fab")
		)
		(fp_line
			(start 0.67945 0.3048)
			(end 0.120396 0.3048)
			(stroke
				(width 0.1)
				(type default)
			)
			(layer "F.Fab")
		)
		(fp_line
			(start -0.12065 0.2794)
			(end -0.12065 0.3048)
			(stroke
				(width 0.1)
				(type default)
			)
			(layer "F.Fab")
		)
		(fp_line
			(start 0.120396 0.2794)
			(end -0.12065 0.2794)
			(stroke
				(width 0.1)
				(type default)
			)
			(layer "F.Fab")
		)
		(fp_line
			(start -0.12065 -0.2794)
			(end 0.12065 -0.2794)
			(stroke
				(width 0.1)
				(type default)
			)
			(layer "F.Fab")
		)
		(fp_line
			(start 0.12065 -0.2794)
			(end 0.12065 -0.3048)
			(stroke
				(width 0.1)
				(type default)
			)
			(layer "F.Fab")
		)
		(fp_line
			(start 0.12065 -0.3048)
			(end 0.67945 -0.3048)
			(stroke
				(width 0.1)
				(type default)
			)
			(layer "F.Fab")
		)
		(fp_line
			(start 0.67945 -0.3048)
			(end 0.67945 0.3048)
			(stroke
				(width 0.1)
				(type default)
			)
			(layer "F.Fab")
		)
		(fp_line
			(start -0.67945 -0.305054)
			(end -0.12065 -0.305054)
			(stroke
				(width 0.1)
				(type default)
			)
			(layer "F.Fab")
		)
		(fp_line
			(start -0.12065 -0.305054)
			(end -0.12065 -0.2794)
			(stroke
				(width 0.1)
				(type default)
			)
			(layer "F.Fab")
		)
		(pad "1" smd circle
			(at -0.40005 0 270)
			(size 0 0)
			(layers "F.Cu" "F.Mask" "F.Paste")
			(net "P3V3_AUX")
		)
		(pad "2" smd circle
			(at 0.40005 0 270)
			(size 0 0)
			(layers "F.Cu" "F.Mask" "F.Paste")
			(net "GND")
		)
	)
	(footprint ""
		(layer "F.Cu")
		(at 447.565272 -19.506438)
		(property "Reference" "PC2087"
			(at 0 0 0)
			(layer "F.SilkS")
			(hide yes)
			(effects
				(font
					(size 1.27 1.27)
				)
			)
		)
		(property "Value" ""
			(at 0 0 0)
			(layer "F.Fab")
			(effects
				(font
					(size 1.27 1.27)
				)
			)
		)
		(duplicate_pad_numbers_are_jumpers no)
		(fp_line
			(start -0.7874 -0.4064)
			(end 0.7874 -0.4064)
			(stroke
				(width 0.1524)
				(type default)
			)
			(layer "F.SilkS")
		)
		(fp_line
			(start -0.7874 0.4064)
			(end -0.7874 -0.4064)
			(stroke
				(width 0.1524)
				(type default)
			)
			(layer "F.SilkS")
		)
		(fp_line
			(start 0.7874 -0.4064)
			(end 0.7874 0.4064)
			(stroke
				(width 0.1524)
				(type default)
			)
			(layer "F.SilkS")
		)
		(fp_line
			(start 0.7874 0.4064)
			(end -0.7874 0.4064)
			(stroke
				(width 0.1524)
				(type default)
			)
			(layer "F.SilkS")
		)
		(fp_line
			(start -0.67945 -0.305054)
			(end -0.12065 -0.305054)
			(stroke
				(width 0.1)
				(type default)
			)
			(layer "F.Fab")
		)
		(fp_line
			(start -0.67945 0.3048)
			(end -0.67945 -0.305054)
			(stroke
				(width 0.1)
				(type default)
			)
			(layer "F.Fab")
		)
		(fp_line
			(start -0.12065 -0.305054)
			(end -0.12065 -0.2794)
			(stroke
				(width 0.1)
				(type default)
			)
			(layer "F.Fab")
		)
		(fp_line
			(start -0.12065 -0.2794)
			(end 0.12065 -0.2794)
			(stroke
				(width 0.1)
				(type default)
			)
			(layer "F.Fab")
		)
		(fp_line
			(start -0.12065 0.2794)
			(end -0.12065 0.3048)
			(stroke
				(width 0.1)
				(type default)
			)
			(layer "F.Fab")
		)
		(fp_line
			(start -0.12065 0.3048)
			(end -0.67945 0.3048)
			(stroke
				(width 0.1)
				(type default)
			)
			(layer "F.Fab")
		)
		(fp_line
			(start 0.120396 0.2794)
			(end -0.12065 0.2794)
			(stroke
				(width 0.1)
				(type default)
			)
			(layer "F.Fab")
		)
		(fp_line
			(start 0.120396 0.3048)
			(end 0.120396 0.2794)
			(stroke
				(width 0.1)
				(type default)
			)
			(layer "F.Fab")
		)
		(fp_line
			(start 0.12065 -0.3048)
			(end 0.67945 -0.3048)
			(stroke
				(width 0.1)
				(type default)
			)
			(layer "F.Fab")
		)
		(fp_line
			(start 0.12065 -0.2794)
			(end 0.12065 -0.3048)
			(stroke
				(width 0.1)
				(type default)
			)
			(layer "F.Fab")
		)
		(fp_line
			(start 0.67945 -0.3048)
			(end 0.67945 0.3048)
			(stroke
				(width 0.1)
				(type default)
			)
			(layer "F.Fab")
		)
		(fp_line
			(start 0.67945 0.3048)
			(end 0.120396 0.3048)
			(stroke
				(width 0.1)
				(type default)
			)
			(layer "F.Fab")
		)
		(pad "1" smd circle
			(at -0.40005 0)
			(size 0 0)
			(layers "F.Cu" "F.Mask" "F.Paste")
			(net "GND")
		)
		(pad "2" smd circle
			(at 0.40005 0)
			(size 0 0)
			(layers "F.Cu" "F.Mask" "F.Paste")
			(net "P12V_OCP_REG_1")
		)
	)
	(footprint ""
		(layer "F.Cu")
		(at 187.552584 -348.31655 180)
		(property "Reference" "PC255"
			(at 0 0 180)
			(layer "F.SilkS")
			(hide yes)
			(effects
				(font
					(size 1.27 1.27)
				)
			)
		)
		(property "Value" ""
			(at 0 0 180)
			(layer "F.Fab")
			(effects
				(font
					(size 1.27 1.27)
				)
			)
		)
		(duplicate_pad_numbers_are_jumpers no)
		(fp_line
			(start 0.7874 0.4064)
			(end -0.7874 0.4064)
			(stroke
				(width 0.1524)
				(type default)
			)
			(layer "F.SilkS")
		)
		(fp_line
			(start 0.7874 -0.4064)
			(end 0.7874 0.4064)
			(stroke
				(width 0.1524)
				(type default)
			)
			(layer "F.SilkS")
		)
		(fp_line
			(start -0.7874 0.4064)
			(end -0.7874 -0.4064)
			(stroke
				(width 0.1524)
				(type default)
			)
			(layer "F.SilkS")
		)
		(fp_line
			(start -0.7874 -0.4064)
			(end 0.7874 -0.4064)
			(stroke
				(width 0.1524)
				(type default)
			)
			(layer "F.SilkS")
		)
		(fp_line
			(start 0.67945 0.3048)
			(end 0.120396 0.3048)
			(stroke
				(width 0.1)
				(type default)
			)
			(layer "F.Fab")
		)
		(fp_line
			(start 0.67945 -0.3048)
			(end 0.67945 0.3048)
			(stroke
				(width 0.1)
				(type default)
			)
			(layer "F.Fab")
		)
		(fp_line
			(start 0.12065 -0.2794)
			(end 0.12065 -0.3048)
			(stroke
				(width 0.1)
				(type default)
			)
			(layer "F.Fab")
		)
		(fp_line
			(start 0.12065 -0.3048)
			(end 0.67945 -0.3048)
			(stroke
				(width 0.1)
				(type default)
			)
			(layer "F.Fab")
		)
		(fp_line
			(start 0.120396 0.3048)
			(end 0.120396 0.2794)
			(stroke
				(width 0.1)
				(type default)
			)
			(layer "F.Fab")
		)
		(fp_line
			(start 0.120396 0.2794)
			(end -0.12065 0.2794)
			(stroke
				(width 0.1)
				(type default)
			)
			(layer "F.Fab")
		)
		(fp_line
			(start -0.12065 0.3048)
			(end -0.67945 0.3048)
			(stroke
				(width 0.1)
				(type default)
			)
			(layer "F.Fab")
		)
		(fp_line
			(start -0.12065 0.2794)
			(end -0.12065 0.3048)
			(stroke
				(width 0.1)
				(type default)
			)
			(layer "F.Fab")
		)
		(fp_line
			(start -0.12065 -0.2794)
			(end 0.12065 -0.2794)
			(stroke
				(width 0.1)
				(type default)
			)
			(layer "F.Fab")
		)
		(fp_line
			(start -0.12065 -0.305054)
			(end -0.12065 -0.2794)
			(stroke
				(width 0.1)
				(type default)
			)
			(layer "F.Fab")
		)
		(fp_line
			(start -0.67945 0.3048)
			(end -0.67945 -0.305054)
			(stroke
				(width 0.1)
				(type default)
			)
			(layer "F.Fab")
		)
		(fp_line
			(start -0.67945 -0.305054)
			(end -0.12065 -0.305054)
			(stroke
				(width 0.1)
				(type default)
			)
			(layer "F.Fab")
		)
		(pad "1" smd circle
			(at -0.40005 0 180)
			(size 0 0)
			(layers "F.Cu" "F.Mask" "F.Paste")
			(net "SW_PVDD11_S3_P1_SW2")
		)
		(pad "2" smd circle
			(at 0.40005 0 180)
			(size 0 0)
			(layers "F.Cu" "F.Mask" "F.Paste")
			(net "SW_PVDD11_S3_P1_SW2_RC")
		)
	)
	(footprint ""
		(layer "F.Cu")
		(at 441.446666 -401.04187 90)
		(property "Reference" "PR6556"
			(at 0 0 90)
			(layer "F.SilkS")
			(hide yes)
			(effects
				(font
					(size 1.27 1.27)
				)
			)
		)
		(property "Value" ""
			(at 0 0 90)
			(layer "F.Fab")
			(effects
				(font
					(size 1.27 1.27)
				)
			)
		)
		(duplicate_pad_numbers_are_jumpers no)
		(fp_line
			(start 0.7874 -0.4064)
			(end 0.7874 0.4064)
			(stroke
				(width 0.1524)
				(type default)
			)
			(layer "F.SilkS")
		)
		(fp_line
			(start -0.7874 -0.4064)
			(end 0.7874 -0.4064)
			(stroke
				(width 0.1524)
				(type default)
			)
			(layer "F.SilkS")
		)
		(fp_line
			(start -0.7874 -0.121666)
			(end -0.7874 -0.4064)
			(stroke
				(width 0.1524)
				(type default)
			)
			(layer "F.SilkS")
		)
		(fp_line
			(start 0.7874 0.4064)
			(end -0.28067 0.4064)
			(stroke
				(width 0.1524)
				(type default)
			)
			(layer "F.SilkS")
		)
		(fp_line
			(start -0.12065 -0.305054)
			(end -0.12065 -0.2794)
			(stroke
				(width 0.1)
				(type default)
			)
			(layer "F.Fab")
		)
		(fp_line
			(start -0.67945 -0.305054)
			(end -0.12065 -0.305054)
			(stroke
				(width 0.1)
				(type default)
			)
			(layer "F.Fab")
		)
		(fp_line
			(start 0.67945 -0.3048)
			(end 0.67945 0.3048)
			(stroke
				(width 0.1)
				(type default)
			)
			(layer "F.Fab")
		)
		(fp_line
			(start 0.12065 -0.3048)
			(end 0.67945 -0.3048)
			(stroke
				(width 0.1)
				(type default)
			)
			(layer "F.Fab")
		)
		(fp_line
			(start 0.12065 -0.2794)
			(end 0.12065 -0.3048)
			(stroke
				(width 0.1)
				(type default)
			)
			(layer "F.Fab")
		)
		(fp_line
			(start -0.12065 -0.2794)
			(end 0.12065 -0.2794)
			(stroke
				(width 0.1)
				(type default)
			)
			(layer "F.Fab")
		)
		(fp_line
			(start 0.120396 0.2794)
			(end -0.12065 0.2794)
			(stroke
				(width 0.1)
				(type default)
			)
			(layer "F.Fab")
		)
		(fp_line
			(start -0.12065 0.2794)
			(end -0.12065 0.3048)
			(stroke
				(width 0.1)
				(type default)
			)
			(layer "F.Fab")
		)
		(fp_line
			(start 0.67945 0.3048)
			(end 0.120396 0.3048)
			(stroke
				(width 0.1)
				(type default)
			)
			(layer "F.Fab")
		)
		(fp_line
			(start 0.120396 0.3048)
			(end 0.120396 0.2794)
			(stroke
				(width 0.1)
				(type default)
			)
			(layer "F.Fab")
		)
		(fp_line
			(start -0.12065 0.3048)
			(end -0.67945 0.3048)
			(stroke
				(width 0.1)
				(type default)
			)
			(layer "F.Fab")
		)
		(fp_line
			(start -0.67945 0.3048)
			(end -0.67945 -0.305054)
			(stroke
				(width 0.1)
				(type default)
			)
			(layer "F.Fab")
		)
		(pad "1" smd circle
			(at -0.40005 0 90)
			(size 0 0)
			(layers "F.Cu" "F.Mask" "F.Paste")
			(net "P0V9_RETIMER_CPU0_VOS1")
		)
		(pad "2" smd circle
			(at 0.40005 0 90)
			(size 0 0)
			(layers "F.Cu" "F.Mask" "F.Paste")
			(net "P0V9_CPU0_RT_2D")
		)
	)
	(footprint ""
		(layer "F.Cu")
		(at 100.342192 -31.795212 90)
		(property "Reference" "R6329"
			(at 0 0 90)
			(layer "F.SilkS")
			(hide yes)
			(effects
				(font
					(size 1.27 1.27)
				)
			)
		)
		(property "Value" ""
			(at 0 0 90)
			(layer "F.Fab")
			(effects
				(font
					(size 1.27 1.27)
				)
			)
		)
		(duplicate_pad_numbers_are_jumpers no)
		(fp_line
			(start 0.7874 -0.4064)
			(end 0.7874 0.4064)
			(stroke
				(width 0.1524)
				(type default)
			)
			(layer "F.SilkS")
		)
		(fp_line
			(start -0.7874 -0.4064)
			(end 0.7874 -0.4064)
			(stroke
				(width 0.1524)
				(type default)
			)
			(layer "F.SilkS")
		)
		(fp_line
			(start 0.7874 0.4064)
			(end -0.7874 0.4064)
			(stroke
				(width 0.1524)
				(type default)
			)
			(layer "F.SilkS")
		)
		(fp_line
			(start -0.7874 0.4064)
			(end -0.7874 -0.4064)
			(stroke
				(width 0.1524)
				(type default)
			)
			(layer "F.SilkS")
		)
		(fp_line
			(start -0.12065 -0.305054)
			(end -0.12065 -0.2794)
			(stroke
				(width 0.1)
				(type default)
			)
			(layer "F.Fab")
		)
		(fp_line
			(start -0.67945 -0.305054)
			(end -0.12065 -0.305054)
			(stroke
				(width 0.1)
				(type default)
			)
			(layer "F.Fab")
		)
		(fp_line
			(start 0.67945 -0.3048)
			(end 0.67945 0.3048)
			(stroke
				(width 0.1)
				(type default)
			)
			(layer "F.Fab")
		)
		(fp_line
			(start 0.12065 -0.3048)
			(end 0.67945 -0.3048)
			(stroke
				(width 0.1)
				(type default)
			)
			(layer "F.Fab")
		)
		(fp_line
			(start 0.12065 -0.2794)
			(end 0.12065 -0.3048)
			(stroke
				(width 0.1)
				(type default)
			)
			(layer "F.Fab")
		)
		(fp_line
			(start -0.12065 -0.2794)
			(end 0.12065 -0.2794)
			(stroke
				(width 0.1)
				(type default)
			)
			(layer "F.Fab")
		)
		(fp_line
			(start 0.120396 0.2794)
			(end -0.12065 0.2794)
			(stroke
				(width 0.1)
				(type default)
			)
			(layer "F.Fab")
		)
		(fp_line
			(start -0.12065 0.2794)
			(end -0.12065 0.3048)
			(stroke
				(width 0.1)
				(type default)
			)
			(layer "F.Fab")
		)
		(fp_line
			(start 0.67945 0.3048)
			(end 0.120396 0.3048)
			(stroke
				(width 0.1)
				(type default)
			)
			(layer "F.Fab")
		)
		(fp_line
			(start 0.120396 0.3048)
			(end 0.120396 0.2794)
			(stroke
				(width 0.1)
				(type default)
			)
			(layer "F.Fab")
		)
		(fp_line
			(start -0.12065 0.3048)
			(end -0.67945 0.3048)
			(stroke
				(width 0.1)
				(type default)
			)
			(layer "F.Fab")
		)
		(fp_line
			(start -0.67945 0.3048)
			(end -0.67945 -0.305054)
			(stroke
				(width 0.1)
				(type default)
			)
			(layer "F.Fab")
		)
		(pad "1" smd circle
			(at -0.40005 0 90)
			(size 0 0)
			(layers "F.Cu" "F.Mask" "F.Paste")
			(net "P3V3_AUX")
		)
		(pad "2" smd circle
			(at 0.40005 0 90)
			(size 0 0)
			(layers "F.Cu" "F.Mask" "F.Paste")
			(net "USB_HUB2_TI_GRSTZ_MRP_PROG_FUNC1")
		)
	)
	(footprint ""
		(layer "F.Cu")
		(at 152.982676 -50.739294 90)
		(property "Reference" "R3595"
			(at 0 0 90)
			(layer "F.SilkS")
			(hide yes)
			(effects
				(font
					(size 1.27 1.27)
				)
			)
		)
		(property "Value" ""
			(at 0 0 90)
			(layer "F.Fab")
			(effects
				(font
					(size 1.27 1.27)
				)
			)
		)
		(duplicate_pad_numbers_are_jumpers no)
		(fp_line
			(start 0.7874 -0.4064)
			(end 0.7874 0.4064)
			(stroke
				(width 0.1524)
				(type default)
			)
			(layer "F.SilkS")
		)
		(fp_line
			(start -0.7874 -0.4064)
			(end 0.7874 -0.4064)
			(stroke
				(width 0.1524)
				(type default)
			)
			(layer "F.SilkS")
		)
		(fp_line
			(start 0.7874 0.4064)
			(end -0.7874 0.4064)
			(stroke
				(width 0.1524)
				(type default)
			)
			(layer "F.SilkS")
		)
		(fp_line
			(start -0.7874 0.4064)
			(end -0.7874 -0.4064)
			(stroke
				(width 0.1524)
				(type default)
			)
			(layer "F.SilkS")
		)
		(fp_line
			(start -0.12065 -0.305054)
			(end -0.12065 -0.2794)
			(stroke
				(width 0.1)
				(type default)
			)
			(layer "F.Fab")
		)
		(fp_line
			(start -0.67945 -0.305054)
			(end -0.12065 -0.305054)
			(stroke
				(width 0.1)
				(type default)
			)
			(layer "F.Fab")
		)
		(fp_line
			(start 0.67945 -0.3048)
			(end 0.67945 0.3048)
			(stroke
				(width 0.1)
				(type default)
			)
			(layer "F.Fab")
		)
		(fp_line
			(start 0.12065 -0.3048)
			(end 0.67945 -0.3048)
			(stroke
				(width 0.1)
				(type default)
			)
			(layer "F.Fab")
		)
		(fp_line
			(start 0.12065 -0.2794)
			(end 0.12065 -0.3048)
			(stroke
				(width 0.1)
				(type default)
			)
			(layer "F.Fab")
		)
		(fp_line
			(start -0.12065 -0.2794)
			(end 0.12065 -0.2794)
			(stroke
				(width 0.1)
				(type default)
			)
			(layer "F.Fab")
		)
		(fp_line
			(start 0.120396 0.2794)
			(end -0.12065 0.2794)
			(stroke
				(width 0.1)
				(type default)
			)
			(layer "F.Fab")
		)
		(fp_line
			(start -0.12065 0.2794)
			(end -0.12065 0.3048)
			(stroke
				(width 0.1)
				(type default)
			)
			(layer "F.Fab")
		)
		(fp_line
			(start 0.67945 0.3048)
			(end 0.120396 0.3048)
			(stroke
				(width 0.1)
				(type default)
			)
			(layer "F.Fab")
		)
		(fp_line
			(start 0.120396 0.3048)
			(end 0.120396 0.2794)
			(stroke
				(width 0.1)
				(type default)
			)
			(layer "F.Fab")
		)
		(fp_line
			(start -0.12065 0.3048)
			(end -0.67945 0.3048)
			(stroke
				(width 0.1)
				(type default)
			)
			(layer "F.Fab")
		)
		(fp_line
			(start -0.67945 0.3048)
			(end -0.67945 -0.305054)
			(stroke
				(width 0.1)
				(type default)
			)
			(layer "F.Fab")
		)
		(pad "1" smd circle
			(at -0.40005 0 90)
			(size 0 0)
			(layers "F.Cu" "F.Mask" "F.Paste")
			(net "SMB_INA230_3V3AUX_SDA")
		)
		(pad "2" smd circle
			(at 0.40005 0 90)
			(size 0 0)
			(layers "F.Cu" "F.Mask" "F.Paste")
			(net "SMB_INA230_4_3V3AUX_SDA_R")
		)
	)
)
